FILE_TYPE = MACRO_DRAWING;
SET COLOR_WIRE YELLOW;
SET COLOR_PROP ORANGE;
SET COLOR_DOT WHITE;
SET COLOR_ARC YELLOW;
SET COLOR_BODY GREEN;
SET COLOR_NOTE PURPLE;
SET PROP_DISPLAY VALUE;
SET PAGE_NUMBER P7;
FORCEADD QUANTA_TITLE_BLOCK_C..1
(-100 100);
FORCEPROP 1 LAST CUSTOM_TXT_CDS <NAME_2>
J 0
(-3275 150);
FORCEPROP 1 LAST CUSTOM_TXT_CDS <NAME_1>
J 0
(-3275 275);
FORCEPROP 1 LAST CUSTOM_TXT_CDS <Q_NUMBER>
J 0
(-1503 203);
DISPLAY 1.212766 (-1503 203);
FORCEPROP 1 LAST CUSTOM_TXT_CDS <Q_PROJ>
J 0
(-2482 202);
DISPLAY 1.212766 (-2482 202);
FORCEPROP 1 LAST CUSTOM_TXT_CDS <Q_REV>
J 0
(-284 203);
DISPLAY 1.212766 (-284 203);
FORCEPROP 1 LAST CUSTOM_TXT_CDS <CON_LAST_MODIFIED>
J 0
(-1985 115);
DISPLAY 0.978723 (-1985 115);
FORCEPROP 1 LAST CUSTOM_TXT_CDS <CON_PAGE_NUM> OF <CON_TOTAL_PAGES>
J 0
(-546 118);
DISPLAY 0.978723 (-546 118);
FORCEPROP 1 LAST Q_TITLE BLOCK DIAGRAM - CLOCK
J 0
(-9425 125);
DISPLAY 2.446809 (-9425 125);
PAINT GREEN (-9425 125);
FORCEPROP 1 LAST CDS_LMAN_SYM_OUTLINE -9475,6775,100,-125
J 0
(-100 100);
DISPLAY 0.468085 (-100 100);
PAINT GREEN (-100 100);
DISPLAY INVISIBLE (-100 100);
FORCEPROP 2 LAST CDS_LIB pure_quanta
J 0
(-100 100);
DISPLAY INVISIBLE (-100 100);
FORCEPROP 2 LAST PAGE_BORDER TRUE
J 0
(-7990 5350);
DISPLAY 0.638298 (-7990 5350);
PAINT PINK (-7990 5350);
DISPLAY INVISIBLE (-7990 5350);
FORCEPROP 2 LAST CDS_XR_PAGE_TITLE CR-7 : @T6G_MB_LIB.T6G(SCH_1):PAGE7
J 0
(-7990 5350);
DISPLAY 0.638298 (-7990 5350);
PAINT PINK (-7990 5350);
DISPLAY INVISIBLE (-7990 5350);
FORCEPROP 2 LAST CUSTOM_TXT_CDS <XR_PAGE_TITLE>
J 0
(-7990 5350);
DISPLAY 0.638298 (-7990 5350);
PAINT PINK (-7990 5350);
DISPLAY INVISIBLE (-7990 5350);
FORCEPROP 1 LAST COMMENT_BODY TRUE
J 0
(-88 87);
DISPLAY 0.978723 (-88 87);
PAINT GREEN (-88 87);
DISPLAY INVISIBLE (-88 87);
FORCEPROP 1 LAST Q_DEPT BU9
J 1
(-3863 149);
DISPLAY 1.957447 (-3863 149);
PAINT GREEN (-3863 149);
DISPLAY INVISIBLE (-3863 149);
FORCEPROP 0 LAST CDS_CON_LAST_MODIFIED Thu Aug 24 10:13:30 2023
J 0
(-1985 115);
DISPLAY INVISIBLE (-1985 115);
FORCENOTE
$CDS_IMAGE|Grand_Teton_Inference_8 Retimer_Block_Diagram_20230203_REV3-CLOCK Topology.jpg|8962|3485
(-4775 3675) 0;
DISPLAY LEFT (-4775 3675);
QUIT
